(kicad_pcb
	(version 20241229)
	(generator "pcbnew")
	(generator_version "9.0")
	(general
		(thickness 1.61)
		(legacy_teardrops no)
	)
	(paper "A3")
	(title_block
		(title "RDIMM DDR5 Tester")
		(date "2026-05-21")
		(rev "2.2.0")
		(company "Antmicro")
		(comment 9 "footprints 245-248 of 796")
	)
	(layers
		(0 "F.Cu" signal)
		(4 "In1.Cu" power)
		(6 "In2.Cu" mixed)
		(8 "In3.Cu" power)
		(10 "In4.Cu" mixed)
		(12 "In5.Cu" power)
		(14 "In6.Cu" mixed)
		(16 "In7.Cu" power)
		(18 "In8.Cu" power)
		(20 "In9.Cu" mixed)
		(22 "In10.Cu" power)
		(2 "B.Cu" signal)
		(9 "F.Adhes" user "F.Adhesive")
		(11 "B.Adhes" user "B.Adhesive")
		(13 "F.Paste" user)
		(15 "B.Paste" user)
		(5 "F.SilkS" user "F.Silkscreen")
		(7 "B.SilkS" user "B.Silkscreen")
		(1 "F.Mask" user)
		(3 "B.Mask" user)
		(17 "Dwgs.User" user "User.Drawings")
		(19 "Cmts.User" user "User.Comments")
		(21 "Eco1.User" user "User.Eco1")
		(23 "Eco2.User" user "User.Eco2")
		(25 "Edge.Cuts" user)
		(27 "Margin" user)
		(31 "F.CrtYd" user "F.Courtyard")
		(29 "B.CrtYd" user "B.Courtyard")
		(35 "F.Fab" user)
		(33 "B.Fab" user)
	)
	(footprint "antmicro-footprints:NetTie-2_SMD_Pad0.127mm"
		(layer "F.Cu")
		(at 257.447 165.62)
		(descr "Net tie, 2 pin, 0.127mm  SMD pads")
		(tags "net tie")
		(property "Reference" "NT3"
			(at -0.128 -1.345 0)
			(layer "F.SilkS")
			(hide yes)
			(effects
				(font
					(size 0.7 0.7)
					(thickness 0.15)
				)
				(justify left bottom)
			)
		)
		(property "Value" "Net-Tie_P0.127mm"
			(at 0 1.199 0)
			(layer "F.Fab")
			(effects
				(font
					(size 0.7 0.7)
					(thickness 0.15)
				)
				(justify left bottom)
			)
		)
		(property "MPN" ""
			(at 0 0 0)
			(unlocked yes)
			(layer "F.Fab")
			(hide yes)
			(effects
				(font
					(size 1 1)
					(thickness 0.15)
				)
			)
		)
		(property "Manufacturer" ""
			(at 0 0 0)
			(unlocked yes)
			(layer "F.Fab")
			(hide yes)
			(effects
				(font
					(size 1 1)
					(thickness 0.15)
				)
			)
		)
		(property "Author" "Antmicro"
			(at 0 0 0)
			(unlocked yes)
			(layer "F.Fab")
			(hide yes)
			(effects
				(font
					(size 1 1)
					(thickness 0.15)
				)
			)
		)
		(property "License" "Apache-2.0"
			(at 0 0 0)
			(unlocked yes)
			(layer "F.Fab")
			(hide yes)
			(effects
				(font
					(size 1 1)
					(thickness 0.15)
				)
			)
		)
		(property ki_fp_filters "Net*Tie*")
		(sheetname "/Supply/DC-DC AUX, MGT/")
		(sheetfile "dc-dc-aux-mgt.kicad_sch")
		(attr through_hole exclude_from_pos_files exclude_from_bom)
		(net_tie_pad_groups "1, 2")
		(fp_poly
			(pts
				(xy -0.0635 -0.0635) (xy 0.0625 -0.0635) (xy 0.0625 0.0635) (xy -0.0635 0.0635)
			)
			(stroke
				(width 0)
				(type solid)
			)
			(fill yes)
			(layer "F.Cu")
		)
		(fp_poly
			(pts
				(xy 0.2 -0.16) (xy 0.29 -0.07) (xy 0.29 0.07) (xy 0.2 0.16) (xy -0.2 0.16) (xy -0.29 0.07) (xy -0.29 -0.06)
				(xy -0.19 -0.16)
			)
			(stroke
				(width 0.05)
				(type solid)
			)
			(fill no)
			(layer "F.CrtYd")
		)
		(fp_text user "Author: Antmicro"
			(at -0.128 4.4 0)
			(layer "F.Fab")
			(effects
				(font
					(size 0.7 0.7)
					(thickness 0.15)
				)
				(justify left bottom)
			)
		)
		(fp_text user "${REFERENCE}"
			(at -0.128 3.2 0)
			(layer "F.Fab")
			(effects
				(font
					(size 0.7 0.7)
					(thickness 0.15)
				)
				(justify left bottom)
			)
		)
		(fp_text user "License: Apache-2.0"
			(at -0.128 5.6 0)
			(layer "F.Fab")
			(effects
				(font
					(size 0.7 0.7)
					(thickness 0.15)
				)
				(justify left bottom)
			)
		)
		(pad "1" smd roundrect
			(at -0.127 0 180)
			(size 0.127 0.127)
			(layers "F.Cu")
			(roundrect_rratio 0.5)
			(chamfer_ratio 0)
			(chamfer top_left bottom_left)
			(net 683 "/Supply/DC-DC AUX, MGT/MGTAVCC_SEN_+")
			(pinfunction "1")
			(pintype "passive")
		)
		(pad "2" smd roundrect
			(at 0.126 0)
			(size 0.127 0.127)
			(layers "F.Cu")
			(roundrect_rratio 0.5)
			(chamfer_ratio 0)
			(chamfer top_left bottom_left)
			(net 47 "/Supply/DC-DC AUX, MGT/MGTAVCC_local")
			(pinfunction "2")
			(pintype "passive")
		)
	)
	(footprint "antmicro-footprints:C_0402_1005Metric"
		(layer "F.Cu")
		(at 164.45 163.064999)
		(descr "Capacitor SMD 0402")
		(tags "capacitor SMD 0402")
		(property "Reference" "C308"
			(at 0.84 0.4 0)
			(layer "F.SilkS")
			(effects
				(font
					(size 0.7 0.7)
					(thickness 0.15)
				)
				(justify left bottom)
			)
		)
		(property "Value" "C_100n_0402"
			(at -1.022927 2.155213 0)
			(layer "F.Fab")
			(effects
				(font
					(size 0.7 0.7)
					(thickness 0.15)
				)
				(justify left bottom)
			)
		)
		(property "Datasheet" "https://www.murata.com/products/productdetail?partno=GRM155R61H104KE14%23"
			(at 0 0 0)
			(layer "F.Fab")
			(hide yes)
			(effects
				(font
					(size 1.27 1.27)
					(thickness 0.15)
				)
			)
		)
		(property "Manufacturer" "Murata"
			(at 0 0 0)
			(unlocked yes)
			(layer "F.Fab")
			(hide yes)
			(effects
				(font
					(size 1 1)
					(thickness 0.15)
				)
			)
		)
		(property "MPN" "GRM155R61H104KE14D"
			(at 0 0 0)
			(unlocked yes)
			(layer "F.Fab")
			(hide yes)
			(effects
				(font
					(size 1 1)
					(thickness 0.15)
				)
			)
		)
		(property "Val" "100n"
			(at 0 0 0)
			(unlocked yes)
			(layer "F.Fab")
			(hide yes)
			(effects
				(font
					(size 1 1)
					(thickness 0.15)
				)
			)
		)
		(property "License" "Apache-2.0"
			(at 0 0 0)
			(unlocked yes)
			(layer "F.Fab")
			(hide yes)
			(effects
				(font
					(size 1 1)
					(thickness 0.15)
				)
			)
		)
		(property "Author" "Antmicro"
			(at 0 0 0)
			(unlocked yes)
			(layer "F.Fab")
			(hide yes)
			(effects
				(font
					(size 1 1)
					(thickness 0.15)
				)
			)
		)
		(property "Voltage" "50V"
			(at 0 0 0)
			(unlocked yes)
			(layer "F.Fab")
			(hide yes)
			(effects
				(font
					(size 1 1)
					(thickness 0.15)
				)
			)
		)
		(property "Dielectric" "X5R"
			(at 0 0 0)
			(unlocked yes)
			(layer "F.Fab")
			(hide yes)
			(effects
				(font
					(size 1 1)
					(thickness 0.15)
				)
			)
		)
		(sheetname "/FPGA MGT Interface/")
		(sheetfile "fpga-mgt.kicad_sch")
		(attr smd)
		(fp_rect
			(start -0.925 -0.47)
			(end 0.925 0.47)
			(stroke
				(width 0.05)
				(type default)
			)
			(fill no)
			(layer "F.CrtYd")
		)
		(fp_line
			(start -0.494 -0.25)
			(end 0.504 -0.25)
			(stroke
				(width 0.15)
				(type solid)
			)
			(layer "F.Fab")
		)
		(fp_line
			(start -0.494 0.248)
			(end -0.494 -0.25)
			(stroke
				(width 0.15)
				(type solid)
			)
			(layer "F.Fab")
		)
		(fp_line
			(start 0.504 -0.25)
			(end 0.504 0.248)
			(stroke
				(width 0.15)
				(type solid)
			)
			(layer "F.Fab")
		)
		(fp_line
			(start 0.504 0.248)
			(end -0.494 0.248)
			(stroke
				(width 0.15)
				(type solid)
			)
			(layer "F.Fab")
		)
		(fp_text user "License: Apache-2.0"
			(at -0.939 5.799 0)
			(layer "F.Fab")
			(effects
				(font
					(size 0.7 0.7)
					(thickness 0.15)
				)
				(justify left bottom)
			)
		)
		(fp_text user "${REFERENCE}"
			(at -0.939 4.599 0)
			(layer "F.Fab")
			(effects
				(font
					(size 0.7 0.7)
					(thickness 0.15)
				)
				(justify left bottom)
			)
		)
		(fp_text user "Author: Antmicro"
			(at -0.939 3.399 0)
			(layer "F.Fab")
			(effects
				(font
					(size 0.7 0.7)
					(thickness 0.15)
				)
				(justify left bottom)
			)
		)
		(pad "1" smd roundrect
			(at -0.48 0)
			(size 0.59 0.64)
			(layers "F.Cu" "F.Mask" "F.Paste")
			(roundrect_rratio 0.25)
			(net 386 "/FPGA MGT Interface/HDMI_SI5319_C_CLK_N")
			(pintype "passive")
		)
		(pad "2" smd roundrect
			(at 0.48 0)
			(size 0.59 0.64)
			(layers "F.Cu" "F.Mask" "F.Paste")
			(roundrect_rratio 0.25)
			(net 387 "/FPGA MGT Interface/HDMI_SI5319_CLK_N")
			(pintype "passive")
		)
	)
	(footprint "antmicro-footprints:WSON-8_2x2mm"
		(layer "F.Cu")
		(at 207.29 154.19)
		(property "Reference" "U35"
			(at -2.99 -1.24 0)
			(unlocked yes)
			(layer "F.SilkS")
			(effects
				(font
					(size 0.7 0.7)
					(thickness 0.15)
				)
				(justify left bottom)
			)
		)
		(property "Value" "TMP451AIDQFR"
			(at 0 2.2 0)
			(unlocked yes)
			(layer "F.Fab")
			(effects
				(font
					(size 0.7 0.7)
					(thickness 0.15)
				)
				(justify left bottom)
			)
		)
		(property "Datasheet" "https://www.ti.com/lit/ds/symlink/tmp451.pdf?ts=1727409102766"
			(at 0 0 0)
			(layer "F.Fab")
			(hide yes)
			(effects
				(font
					(size 1.27 1.27)
					(thickness 0.15)
				)
			)
		)
		(property "MPN" "TMP451AIDQFR"
			(at 0 0 0)
			(unlocked yes)
			(layer "F.Fab")
			(hide yes)
			(effects
				(font
					(size 1 1)
					(thickness 0.15)
				)
			)
		)
		(property "Manufacturer" "Texas Instruments"
			(at 0 0 0)
			(unlocked yes)
			(layer "F.Fab")
			(hide yes)
			(effects
				(font
					(size 1 1)
					(thickness 0.15)
				)
			)
		)
		(property "Author" "Antmicro"
			(at 0 0 0)
			(unlocked yes)
			(layer "F.Fab")
			(hide yes)
			(effects
				(font
					(size 1 1)
					(thickness 0.15)
				)
			)
		)
		(property "License" "Apache-2.0"
			(at 0 0 0)
			(unlocked yes)
			(layer "F.Fab")
			(hide yes)
			(effects
				(font
					(size 1 1)
					(thickness 0.15)
				)
			)
		)
		(sheetname "/FPGA Config/")
		(sheetfile "fpga-config.kicad_sch")
		(attr smd)
		(fp_line
			(start -0.381 -1.13)
			(end 0.381 -1.13)
			(stroke
				(width 0.15)
				(type solid)
			)
			(layer "F.SilkS")
		)
		(fp_line
			(start -0.381 1.13)
			(end 0.381 1.13)
			(stroke
				(width 0.15)
				(type solid)
			)
			(layer "F.SilkS")
		)
		(fp_circle
			(center -1.2 -1.05)
			(end -1.15 -1.05)
			(stroke
				(width 0.15)
				(type solid)
			)
			(fill yes)
			(layer "F.SilkS")
		)
		(fp_rect
			(start -1.3 -1.1)
			(end 1.3 1.1)
			(stroke
				(width 0.05)
				(type solid)
			)
			(fill no)
			(layer "F.CrtYd")
		)
		(fp_line
			(start -1.003 -0.598)
			(end -1.003 1.003)
			(stroke
				(width 0.15)
				(type solid)
			)
			(layer "F.Fab")
		)
		(fp_line
			(start -1.003 -0.598)
			(end -0.635 -1.003)
			(stroke
				(width 0.15)
				(type solid)
			)
			(layer "F.Fab")
		)
		(fp_line
			(start -1.003 -0.402)
			(end -1.003 -0.098)
			(stroke
				(width 0.15)
				(type solid)
			)
			(layer "F.Fab")
		)
		(fp_line
			(start -1.003 -0.402)
			(end -1.003 -0.098)
			(stroke
				(width 0.15)
				(type solid)
			)
			(layer "F.Fab")
		)
		(fp_line
			(start -1.003 0.098)
			(end -1.003 0.402)
			(stroke
				(width 0.15)
				(type solid)
			)
			(layer "F.Fab")
		)
		(fp_line
			(start -1.003 0.098)
			(end -1.003 0.402)
			(stroke
				(width 0.15)
				(type solid)
			)
			(layer "F.Fab")
		)
		(fp_line
			(start -1.003 0.598)
			(end -1.003 0.902)
			(stroke
				(width 0.15)
				(type solid)
			)
			(layer "F.Fab")
		)
		(fp_line
			(start -1.003 0.598)
			(end -1.003 0.902)
			(stroke
				(width 0.15)
				(type solid)
			)
			(layer "F.Fab")
		)
		(fp_line
			(start -1.003 1.003)
			(end 1.003 1.003)
			(stroke
				(width 0.15)
				(type solid)
			)
			(layer "F.Fab")
		)
		(fp_line
			(start -0.635 -1.003)
			(end 1.003 -1.003)
			(stroke
				(width 0.15)
				(type solid)
			)
			(layer "F.Fab")
		)
		(fp_line
			(start 1.003 -1.003)
			(end 1.003 1.003)
			(stroke
				(width 0.15)
				(type solid)
			)
			(layer "F.Fab")
		)
		(fp_line
			(start 1.003 -0.902)
			(end 1.003 -0.598)
			(stroke
				(width 0.15)
				(type solid)
			)
			(layer "F.Fab")
		)
		(fp_line
			(start 1.003 -0.902)
			(end 1.003 -0.598)
			(stroke
				(width 0.15)
				(type solid)
			)
			(layer "F.Fab")
		)
		(fp_line
			(start 1.003 -0.402)
			(end 1.003 -0.098)
			(stroke
				(width 0.15)
				(type solid)
			)
			(layer "F.Fab")
		)
		(fp_line
			(start 1.003 -0.402)
			(end 1.003 -0.098)
			(stroke
				(width 0.15)
				(type solid)
			)
			(layer "F.Fab")
		)
		(fp_line
			(start 1.003 0.098)
			(end 1.003 0.402)
			(stroke
				(width 0.15)
				(type solid)
			)
			(layer "F.Fab")
		)
		(fp_line
			(start 1.003 0.098)
			(end 1.003 0.402)
			(stroke
				(width 0.15)
				(type solid)
			)
			(layer "F.Fab")
		)
		(fp_line
			(start 1.003 0.598)
			(end 1.003 0.902)
			(stroke
				(width 0.15)
				(type solid)
			)
			(layer "F.Fab")
		)
		(fp_line
			(start 1.003 0.598)
			(end 1.003 0.902)
			(stroke
				(width 0.15)
				(type solid)
			)
			(layer "F.Fab")
		)
		(fp_text user "Author: Antmicro"
			(at -1.3 6.6 0)
			(layer "F.Fab")
			(effects
				(font
					(size 0.7 0.7)
					(thickness 0.15)
				)
				(justify left bottom)
			)
		)
		(fp_text user "${REFERENCE}"
			(at -1.3 4.2 0)
			(layer "F.Fab")
			(effects
				(font
					(size 0.7 0.7)
					(thickness 0.15)
				)
				(justify left bottom)
			)
		)
		(fp_text user "License: Apache-2.0"
			(at -1.3 5.4 0)
			(layer "F.Fab")
			(effects
				(font
					(size 0.7 0.7)
					(thickness 0.15)
				)
				(justify left bottom)
			)
		)
		(pad "1" smd rect
			(at -0.8 -0.75 270)
			(size 0.25 0.8)
			(layers "F.Cu" "F.Mask" "F.Paste")
			(net 151 "+3V3")
			(pinfunction "V+")
			(pintype "power_in")
		)
		(pad "2" smd rect
			(at -0.85 -0.25 270)
			(size 0.25 0.7)
			(layers "F.Cu" "F.Mask" "F.Paste")
			(net 668 "/FPGA Config/DX_P")
			(pinfunction "D+")
			(pintype "input")
		)
		(pad "3" smd rect
			(at -0.85 0.25 270)
			(size 0.25 0.7)
			(layers "F.Cu" "F.Mask" "F.Paste")
			(net 667 "/FPGA Config/DX_N")
			(pinfunction "D-")
			(pintype "input")
		)
		(pad "4" smd rect
			(at -0.85 0.75 270)
			(size 0.25 0.7)
			(layers "F.Cu" "F.Mask" "F.Paste")
			(net 705 "/FPGA Config/~{THERM}")
			(pinfunction "~{THERM}")
			(pintype "output")
		)
		(pad "5" smd rect
			(at 0.85 0.75 270)
			(size 0.25 0.7)
			(layers "F.Cu" "F.Mask" "F.Paste")
			(net 1 "GND")
			(pinfunction "GND")
			(pintype "power_in")
		)
		(pad "6" smd rect
			(at 0.85 0.25 270)
			(size 0.25 0.7)
			(layers "F.Cu" "F.Mask" "F.Paste")
			(net 477 "/FPGA Config/~{ALARM}")
			(pinfunction "~{ALERT}")
			(pintype "output")
		)
		(pad "7" smd rect
			(at 0.85 -0.25 270)
			(size 0.25 0.7)
			(layers "F.Cu" "F.Mask" "F.Paste")
			(net 746 "/FPGA Config/FPGA_PWR.SDA")
			(pinfunction "SDA")
			(pintype "bidirectional")
		)
		(pad "8" smd rect
			(at 0.85 -0.75 270)
			(size 0.25 0.7)
			(layers "F.Cu" "F.Mask" "F.Paste")
			(net 747 "/FPGA Config/FPGA_PWR.SCL")
			(pinfunction "SCL")
			(pintype "input")
		)
	)
	(footprint "antmicro-footprints:LED_0402_1005Metric_G"
		(layer "F.Cu")
		(at 104.64 114.725 180)
		(property "Reference" "D2"
			(at 0 -0.6 180)
			(unlocked yes)
			(layer "F.SilkS")
			(hide yes)
			(effects
				(font
					(size 0.7 0.7)
					(thickness 0.15)
				)
				(justify left bottom)
			)
		)
		(property "Value" "LED_G_0402_VLMTG1500-GS08"
			(at 0 1.5 180)
			(unlocked yes)
			(layer "F.Fab")
			(effects
				(font
					(size 0.7 0.7)
					(thickness 0.15)
				)
				(justify left bottom)
			)
		)
		(property "Datasheet" "https://www.vishay.com/docs/82554/vlmo1500.pdf"
			(at 0 0 180)
			(layer "F.Fab")
			(hide yes)
			(effects
				(font
					(size 1.27 1.27)
					(thickness 0.15)
				)
			)
		)
		(property "MPN" "VLMTG1500-GS08"
			(at 0 0 180)
			(unlocked yes)
			(layer "F.Fab")
			(hide yes)
			(effects
				(font
					(size 1 1)
					(thickness 0.15)
				)
			)
		)
		(property "Manufacturer" "Vishay"
			(at 0 0 180)
			(unlocked yes)
			(layer "F.Fab")
			(hide yes)
			(effects
				(font
					(size 1 1)
					(thickness 0.15)
				)
			)
		)
		(property "Color" "Green"
			(at 0 0 180)
			(unlocked yes)
			(layer "F.Fab")
			(hide yes)
			(effects
				(font
					(size 1 1)
					(thickness 0.15)
				)
			)
		)
		(property "Author" "Antmicro"
			(at 0 0 180)
			(unlocked yes)
			(layer "F.Fab")
			(hide yes)
			(effects
				(font
					(size 1 1)
					(thickness 0.15)
				)
			)
		)
		(property "License" "Apache-2.0"
			(at 0 0 180)
			(unlocked yes)
			(layer "F.Fab")
			(hide yes)
			(effects
				(font
					(size 1 1)
					(thickness 0.15)
				)
			)
		)
		(sheetname "/FPGA Config/")
		(sheetfile "fpga-config.kicad_sch")
		(attr smd)
		(fp_line
			(start -0.175 0.4)
			(end 0.175 0.4)
			(stroke
				(width 0.15)
				(type solid)
			)
			(layer "F.SilkS")
		)
		(fp_line
			(start -0.175 -0.4)
			(end 0.175 -0.4)
			(stroke
				(width 0.15)
				(type solid)
			)
			(layer "F.SilkS")
		)
		(fp_line
			(start -0.9 -0.4)
			(end -0.9 0.4)
			(stroke
				(width 0.15)
				(type solid)
			)
			(layer "F.SilkS")
		)
		(fp_rect
			(start -0.925 -0.47)
			(end 0.925 0.47)
			(stroke
				(width 0.05)
				(type default)
			)
			(fill no)
			(layer "F.CrtYd")
		)
		(fp_line
			(start 0.501 0.26)
			(end 0.501 -0.248)
			(stroke
				(width 0.15)
				(type solid)
			)
			(layer "F.Fab")
		)
		(fp_line
			(start 0.501 0.26)
			(end 0.501 -0.248)
			(stroke
				(width 0.15)
				(type solid)
			)
			(layer "F.Fab")
		)
		(fp_line
			(start 0.501 -0.248)
			(end 0.172 -0.248)
			(stroke
				(width 0.15)
				(type solid)
			)
			(layer "F.Fab")
		)
		(fp_line
			(start 0.501 -0.248)
			(end -0.489 -0.248)
			(stroke
				(width 0.15)
				(type solid)
			)
			(layer "F.Fab")
		)
		(fp_line
			(start 0.228 0.202)
			(end 0.228 0)
			(stroke
				(width 0.15)
				(type solid)
			)
			(layer "F.Fab")
		)
		(fp_line
			(start 0.228 0)
			(end 0.228 -0.202)
			(stroke
				(width 0.15)
				(type solid)
			)
			(layer "F.Fab")
		)
		(fp_line
			(start 0.228 -0.202)
			(end -0.074 0)
			(stroke
				(width 0.15)
				(type solid)
			)
			(layer "F.Fab")
		)
		(fp_line
			(start 0.172 0.26)
			(end 0.501 0.26)
			(stroke
				(width 0.15)
				(type solid)
			)
			(layer "F.Fab")
		)
		(fp_line
			(start 0.172 -0.248)
			(end 0.172 0.26)
			(stroke
				(width 0.15)
				(type solid)
			)
			(layer "F.Fab")
		)
		(fp_line
			(start -0.074 0)
			(end 0.228 0.202)
			(stroke
				(width 0.15)
				(type solid)
			)
			(layer "F.Fab")
		)
		(fp_line
			(start -0.158 0.26)
			(end -0.158 -0.248)
			(stroke
				(width 0.15)
				(type solid)
			)
			(layer "F.Fab")
		)
		(fp_line
			(start -0.158 -0.248)
			(end -0.489 -0.248)
			(stroke
				(width 0.15)
				(type solid)
			)
			(layer "F.Fab")
		)
		(fp_line
			(start -0.173 0.202)
			(end -0.173 0.102)
			(stroke
				(width 0.15)
				(type solid)
			)
			(layer "F.Fab")
		)
		(fp_line
			(start -0.173 -0.202)
			(end -0.173 0.102)
			(stroke
				(width 0.15)
				(type solid)
			)
			(layer "F.Fab")
		)
		(fp_line
			(start -0.489 0.26)
			(end 0.501 0.26)
			(stroke
				(width 0.15)
				(type solid)
			)
			(layer "F.Fab")
		)
		(fp_line
			(start -0.489 0.26)
			(end -0.158 0.26)
			(stroke
				(width 0.15)
				(type solid)
			)
			(layer "F.Fab")
		)
		(fp_line
			(start -0.489 -0.248)
			(end -0.489 0.26)
			(stroke
				(width 0.15)
				(type solid)
			)
			(layer "F.Fab")
		)
		(fp_line
			(start -0.489 -0.248)
			(end -0.489 0.26)
			(stroke
				(width 0.15)
				(type solid)
			)
			(layer "F.Fab")
		)
		(fp_text user "License: Apache-2.0"
			(at 0 5.35 180)
			(layer "F.Fab")
			(effects
				(font
					(size 0.7 0.7)
					(thickness 0.15)
				)
				(justify left bottom)
			)
		)
		(fp_text user "Author: Antmicro"
			(at 0 4.15 180)
			(layer "F.Fab")
			(effects
				(font
					(size 0.7 0.7)
					(thickness 0.15)
				)
				(justify left bottom)
			)
		)
		(fp_text user "${REFERENCE}"
			(at 0 2.95 180)
			(unlocked yes)
			(layer "F.Fab")
			(effects
				(font
					(size 0.7 0.7)
					(thickness 0.15)
				)
				(justify left bottom)
			)
		)
		(pad "1" smd roundrect
			(at -0.48 0 180)
			(size 0.59 0.64)
			(layers "F.Cu" "F.Mask" "F.Paste")
			(roundrect_rratio 0.25)
			(net 784 "Net-(D2-C)")
			(pinfunction "C")
			(pintype "passive")
		)
		(pad "2" smd roundrect
			(at 0.48 0 180)
			(size 0.59 0.64)
			(layers "F.Cu" "F.Mask" "F.Paste")
			(roundrect_rratio 0.25)
			(net 151 "+3V3")
			(pinfunction "A")
			(pintype "passive")
		)
	)
)
